(kicad_pcb
	(version 20260206)
	(generator "pcbnew")
	(generator_version "10.0")
	(general
		(thickness 1.6)
		(legacy_teardrops no)
	)
	(paper "A4")
	(title_block
		(title "01162023_DA0F0TEBIF0_F0T_Expander_BD_F_brd_V02_OCP.brd")
		(comment 1 "Grand Teton / footprints 9476-9483 of 9728")
	)
	(layers
		(0 "F.Cu" signal "TOP")
		(4 "In1.Cu" signal "GND")
		(6 "In2.Cu" signal "VCC")
		(8 "In3.Cu" signal "VCC1")
		(10 "In4.Cu" signal "GND1")
		(12 "In5.Cu" signal "IN1")
		(14 "In6.Cu" signal "GND2")
		(16 "In7.Cu" signal "IN2")
		(18 "In8.Cu" signal "GND3")
		(20 "In9.Cu" signal "IN3")
		(22 "In10.Cu" signal "GND4")
		(24 "In11.Cu" signal "IN4")
		(26 "In12.Cu" signal "GND5")
		(28 "In13.Cu" signal "IN5")
		(30 "In14.Cu" signal "GND6")
		(32 "In15.Cu" signal "IN6")
		(34 "In16.Cu" signal "GND7")
		(2 "B.Cu" signal "BOTTOM")
		(9 "F.Adhes" user "F.Adhesive")
		(11 "B.Adhes" user "B.Adhesive")
		(13 "F.Paste" user "Package Geometry/Pastemask Top")
		(15 "B.Paste" user "Package Geometry/Pastemask Bottom")
		(5 "F.SilkS" user "Ref Des/Silkscreen Top")
		(7 "B.SilkS" user "Ref Des/Silkscreen Bottom")
		(1 "F.Mask" user "Board Geometry/Soldermask Top")
		(3 "B.Mask" user "Board Geometry/Soldermask Bottom")
		(17 "Dwgs.User" user "User.Drawings")
		(19 "Cmts.User" user "User.Comments")
		(21 "Eco1.User" user "User.Eco1")
		(23 "Eco2.User" user "User.Eco2")
		(25 "Edge.Cuts" user "Board Geometry/Outline")
		(27 "Margin" user)
		(31 "F.CrtYd" user "Package Geometry/Place Bound Top")
		(29 "B.CrtYd" user "Package Geometry/Place Bound Bottom")
		(35 "F.Fab" user "Ref Des/Assembly Top")
		(33 "B.Fab" user "Ref Des/Assembly Bottom")
	)
	(footprint ""
		(layer "B.Cu")
		(at 329.692 -225.5012)
		(property "Reference" "R4165"
			(at 0 0 0)
			(layer "B.SilkS")
			(hide yes)
			(effects
				(font
					(size 1.27 1.27)
				)
				(justify mirror)
			)
		)
		(property "Value" ""
			(at 0 0 0)
			(layer "B.Fab")
			(effects
				(font
					(size 1.27 1.27)
				)
				(justify mirror)
			)
		)
		(duplicate_pad_numbers_are_jumpers no)
		(fp_line
			(start -0.7874 -0.4064)
			(end -0.7874 0.4064)
			(stroke
				(width 0.1524)
				(type default)
			)
			(layer "B.SilkS")
		)
		(fp_line
			(start -0.7874 0.4064)
			(end 0.7874 0.4064)
			(stroke
				(width 0.1524)
				(type default)
			)
			(layer "B.SilkS")
		)
		(fp_line
			(start 0.7874 -0.4064)
			(end -0.7874 -0.4064)
			(stroke
				(width 0.1524)
				(type default)
			)
			(layer "B.SilkS")
		)
		(fp_line
			(start 0.7874 0.4064)
			(end 0.7874 -0.4064)
			(stroke
				(width 0.1524)
				(type default)
			)
			(layer "B.SilkS")
		)
		(fp_line
			(start -0.67945 -0.3048)
			(end -0.67945 0.3048)
			(stroke
				(width 0.1)
				(type default)
			)
			(layer "B.Fab")
		)
		(fp_line
			(start -0.67945 0.3048)
			(end -0.120396 0.3048)
			(stroke
				(width 0.1)
				(type default)
			)
			(layer "B.Fab")
		)
		(fp_line
			(start -0.12065 -0.3048)
			(end -0.67945 -0.3048)
			(stroke
				(width 0.1)
				(type default)
			)
			(layer "B.Fab")
		)
		(fp_line
			(start -0.12065 -0.2794)
			(end -0.12065 -0.3048)
			(stroke
				(width 0.1)
				(type default)
			)
			(layer "B.Fab")
		)
		(fp_line
			(start -0.120396 0.2794)
			(end 0.12065 0.2794)
			(stroke
				(width 0.1)
				(type default)
			)
			(layer "B.Fab")
		)
		(fp_line
			(start -0.120396 0.3048)
			(end -0.120396 0.2794)
			(stroke
				(width 0.1)
				(type default)
			)
			(layer "B.Fab")
		)
		(fp_line
			(start 0.12065 -0.305054)
			(end 0.12065 -0.2794)
			(stroke
				(width 0.1)
				(type default)
			)
			(layer "B.Fab")
		)
		(fp_line
			(start 0.12065 -0.2794)
			(end -0.12065 -0.2794)
			(stroke
				(width 0.1)
				(type default)
			)
			(layer "B.Fab")
		)
		(fp_line
			(start 0.12065 0.2794)
			(end 0.12065 0.3048)
			(stroke
				(width 0.1)
				(type default)
			)
			(layer "B.Fab")
		)
		(fp_line
			(start 0.12065 0.3048)
			(end 0.67945 0.3048)
			(stroke
				(width 0.1)
				(type default)
			)
			(layer "B.Fab")
		)
		(fp_line
			(start 0.67945 -0.305054)
			(end 0.12065 -0.305054)
			(stroke
				(width 0.1)
				(type default)
			)
			(layer "B.Fab")
		)
		(fp_line
			(start 0.67945 0.3048)
			(end 0.67945 -0.305054)
			(stroke
				(width 0.1)
				(type default)
			)
			(layer "B.Fab")
		)
		(pad "1" smd circle
			(at 0.40005 0 180)
			(size 0 0)
			(layers "B.Cu" "B.Mask" "B.Paste")
			(net "PWR_EN_P1V2_AUX")
		)
		(pad "2" smd circle
			(at -0.40005 0 180)
			(size 0 0)
			(layers "B.Cu" "B.Mask" "B.Paste")
			(net "PWR_EN_P1V2_AUX_R")
		)
	)
	(footprint ""
		(layer "B.Cu")
		(at 52.049934 -303.499774 -90)
		(property "Reference" "C2909"
			(at 0 0 90)
			(layer "B.SilkS")
			(hide yes)
			(effects
				(font
					(size 1.27 1.27)
				)
				(justify mirror)
			)
		)
		(property "Value" ""
			(at 0 0 90)
			(layer "B.Fab")
			(effects
				(font
					(size 1.27 1.27)
				)
				(justify mirror)
			)
		)
		(duplicate_pad_numbers_are_jumpers no)
		(fp_line
			(start -0.299974 0.150114)
			(end 0.299974 0.150114)
			(stroke
				(width 0.1)
				(type default)
			)
			(layer "B.Fab")
		)
		(fp_line
			(start 0.299974 0.150114)
			(end 0.299974 -0.150114)
			(stroke
				(width 0.1)
				(type default)
			)
			(layer "B.Fab")
		)
		(fp_line
			(start -0.299974 -0.150114)
			(end -0.299974 0.150114)
			(stroke
				(width 0.1)
				(type default)
			)
			(layer "B.Fab")
		)
		(fp_line
			(start 0.299974 -0.150114)
			(end -0.299974 -0.150114)
			(stroke
				(width 0.1)
				(type default)
			)
			(layer "B.Fab")
		)
		(pad "1" smd rect
			(at 0.2667 0 90)
			(size 0.3048 0.381)
			(layers "B.Cu" "B.Mask" "B.Paste")
			(net "P1V25_PEX0")
		)
		(pad "2" smd rect
			(at -0.2667 0 90)
			(size 0.3048 0.381)
			(layers "B.Cu" "B.Mask" "B.Paste")
			(net "GND")
		)
	)
	(footprint ""
		(layer "B.Cu")
		(at 133.025896 -170.464226)
		(property "Reference" "R1476"
			(at 0 0 0)
			(layer "B.SilkS")
			(hide yes)
			(effects
				(font
					(size 1.27 1.27)
				)
				(justify mirror)
			)
		)
		(property "Value" ""
			(at 0 0 0)
			(layer "B.Fab")
			(effects
				(font
					(size 1.27 1.27)
				)
				(justify mirror)
			)
		)
		(duplicate_pad_numbers_are_jumpers no)
		(fp_line
			(start -0.7874 -0.4064)
			(end -0.7874 0.4064)
			(stroke
				(width 0.1524)
				(type default)
			)
			(layer "B.SilkS")
		)
		(fp_line
			(start -0.7874 0.4064)
			(end 0.7874 0.4064)
			(stroke
				(width 0.1524)
				(type default)
			)
			(layer "B.SilkS")
		)
		(fp_line
			(start 0.7874 -0.4064)
			(end -0.7874 -0.4064)
			(stroke
				(width 0.1524)
				(type default)
			)
			(layer "B.SilkS")
		)
		(fp_line
			(start 0.7874 0.4064)
			(end 0.7874 -0.4064)
			(stroke
				(width 0.1524)
				(type default)
			)
			(layer "B.SilkS")
		)
		(fp_line
			(start -0.67945 -0.3048)
			(end -0.67945 0.3048)
			(stroke
				(width 0.1)
				(type default)
			)
			(layer "B.Fab")
		)
		(fp_line
			(start -0.67945 0.3048)
			(end -0.120396 0.3048)
			(stroke
				(width 0.1)
				(type default)
			)
			(layer "B.Fab")
		)
		(fp_line
			(start -0.12065 -0.3048)
			(end -0.67945 -0.3048)
			(stroke
				(width 0.1)
				(type default)
			)
			(layer "B.Fab")
		)
		(fp_line
			(start -0.12065 -0.2794)
			(end -0.12065 -0.3048)
			(stroke
				(width 0.1)
				(type default)
			)
			(layer "B.Fab")
		)
		(fp_line
			(start -0.120396 0.2794)
			(end 0.12065 0.2794)
			(stroke
				(width 0.1)
				(type default)
			)
			(layer "B.Fab")
		)
		(fp_line
			(start -0.120396 0.3048)
			(end -0.120396 0.2794)
			(stroke
				(width 0.1)
				(type default)
			)
			(layer "B.Fab")
		)
		(fp_line
			(start 0.12065 -0.305054)
			(end 0.12065 -0.2794)
			(stroke
				(width 0.1)
				(type default)
			)
			(layer "B.Fab")
		)
		(fp_line
			(start 0.12065 -0.2794)
			(end -0.12065 -0.2794)
			(stroke
				(width 0.1)
				(type default)
			)
			(layer "B.Fab")
		)
		(fp_line
			(start 0.12065 0.2794)
			(end 0.12065 0.3048)
			(stroke
				(width 0.1)
				(type default)
			)
			(layer "B.Fab")
		)
		(fp_line
			(start 0.12065 0.3048)
			(end 0.67945 0.3048)
			(stroke
				(width 0.1)
				(type default)
			)
			(layer "B.Fab")
		)
		(fp_line
			(start 0.67945 -0.305054)
			(end 0.12065 -0.305054)
			(stroke
				(width 0.1)
				(type default)
			)
			(layer "B.Fab")
		)
		(fp_line
			(start 0.67945 0.3048)
			(end 0.67945 -0.305054)
			(stroke
				(width 0.1)
				(type default)
			)
			(layer "B.Fab")
		)
		(pad "1" smd circle
			(at 0.40005 0 180)
			(size 0 0)
			(layers "B.Cu" "B.Mask" "B.Paste")
			(net "SMB_BMC_9FGL0451E_SCL")
		)
		(pad "2" smd circle
			(at -0.40005 0 180)
			(size 0 0)
			(layers "B.Cu" "B.Mask" "B.Paste")
			(net "SMB_CLK_ISO_R_SCL")
		)
	)
	(footprint ""
		(layer "B.Cu")
		(at 287.519872 -305.399948 -90)
		(property "Reference" "C3310"
			(at 0 0 90)
			(layer "B.SilkS")
			(hide yes)
			(effects
				(font
					(size 1.27 1.27)
				)
				(justify mirror)
			)
		)
		(property "Value" ""
			(at 0 0 90)
			(layer "B.Fab")
			(effects
				(font
					(size 1.27 1.27)
				)
				(justify mirror)
			)
		)
		(duplicate_pad_numbers_are_jumpers no)
		(fp_line
			(start -0.299974 0.150114)
			(end 0.299974 0.150114)
			(stroke
				(width 0.1)
				(type default)
			)
			(layer "B.Fab")
		)
		(fp_line
			(start 0.299974 0.150114)
			(end 0.299974 -0.150114)
			(stroke
				(width 0.1)
				(type default)
			)
			(layer "B.Fab")
		)
		(fp_line
			(start -0.299974 -0.150114)
			(end -0.299974 0.150114)
			(stroke
				(width 0.1)
				(type default)
			)
			(layer "B.Fab")
		)
		(fp_line
			(start 0.299974 -0.150114)
			(end -0.299974 -0.150114)
			(stroke
				(width 0.1)
				(type default)
			)
			(layer "B.Fab")
		)
		(pad "1" smd rect
			(at 0.2667 0 90)
			(size 0.3048 0.381)
			(layers "B.Cu" "B.Mask" "B.Paste")
			(net "P1V25_SERDES_VDDPLL_PEX2")
		)
		(pad "2" smd rect
			(at -0.2667 0 90)
			(size 0.3048 0.381)
			(layers "B.Cu" "B.Mask" "B.Paste")
			(net "GND")
		)
	)
	(footprint ""
		(layer "B.Cu")
		(at 265.66368 -87.364316 180)
		(property "Reference" "C2644"
			(at 0 0 0)
			(layer "B.SilkS")
			(hide yes)
			(effects
				(font
					(size 1.27 1.27)
				)
				(justify mirror)
			)
		)
		(property "Value" ""
			(at 0 0 0)
			(layer "B.Fab")
			(effects
				(font
					(size 1.27 1.27)
				)
				(justify mirror)
			)
		)
		(duplicate_pad_numbers_are_jumpers no)
		(fp_line
			(start 1.2954 0.5842)
			(end 1.2954 -0.5842)
			(stroke
				(width 0.1524)
				(type default)
			)
			(layer "B.SilkS")
		)
		(fp_line
			(start 1.2954 -0.5842)
			(end -1.2954 -0.5842)
			(stroke
				(width 0.1524)
				(type default)
			)
			(layer "B.SilkS")
		)
		(fp_line
			(start -1.2954 0.5842)
			(end 1.2954 0.5842)
			(stroke
				(width 0.1524)
				(type default)
			)
			(layer "B.SilkS")
		)
		(fp_line
			(start -1.2954 -0.5842)
			(end -1.2954 0.5842)
			(stroke
				(width 0.1524)
				(type default)
			)
			(layer "B.SilkS")
		)
		(fp_line
			(start 1.1938 0.4064)
			(end 1.1938 -0.4064)
			(stroke
				(width 0.1)
				(type default)
			)
			(layer "B.Fab")
		)
		(fp_line
			(start 1.1938 -0.4064)
			(end 0.8636 -0.4064)
			(stroke
				(width 0.1)
				(type default)
			)
			(layer "B.Fab")
		)
		(fp_line
			(start 0.8636 0.4572)
			(end 0.8636 0.4064)
			(stroke
				(width 0.1)
				(type default)
			)
			(layer "B.Fab")
		)
		(fp_line
			(start 0.8636 0.4064)
			(end 1.1938 0.4064)
			(stroke
				(width 0.1)
				(type default)
			)
			(layer "B.Fab")
		)
		(fp_line
			(start 0.8636 -0.4064)
			(end 0.8636 -0.4572)
			(stroke
				(width 0.1)
				(type default)
			)
			(layer "B.Fab")
		)
		(fp_line
			(start 0.8636 -0.4572)
			(end -0.8636 -0.4572)
			(stroke
				(width 0.1)
				(type default)
			)
			(layer "B.Fab")
		)
		(fp_line
			(start -0.8636 0.4572)
			(end 0.8636 0.4572)
			(stroke
				(width 0.1)
				(type default)
			)
			(layer "B.Fab")
		)
		(fp_line
			(start -0.8636 0.4064)
			(end -0.8636 0.4572)
			(stroke
				(width 0.1)
				(type default)
			)
			(layer "B.Fab")
		)
		(fp_line
			(start -0.8636 -0.4064)
			(end -1.1938 -0.4064)
			(stroke
				(width 0.1)
				(type default)
			)
			(layer "B.Fab")
		)
		(fp_line
			(start -0.8636 -0.4572)
			(end -0.8636 -0.4064)
			(stroke
				(width 0.1)
				(type default)
			)
			(layer "B.Fab")
		)
		(fp_line
			(start -1.1938 0.4064)
			(end -0.8636 0.4064)
			(stroke
				(width 0.1)
				(type default)
			)
			(layer "B.Fab")
		)
		(fp_line
			(start -1.1938 -0.4064)
			(end -1.1938 0.4064)
			(stroke
				(width 0.1)
				(type default)
			)
			(layer "B.Fab")
		)
		(pad "1" smd rect
			(at 0.7366 0 90)
			(size 0.7112 0.8128)
			(layers "B.Cu" "B.Mask" "B.Paste")
			(net "P3V3_CLK_GEN_VDDMXCK_CK440")
		)
		(pad "2" smd rect
			(at -0.7366 0 90)
			(size 0.7112 0.8128)
			(layers "B.Cu" "B.Mask" "B.Paste")
			(net "GND")
		)
	)
	(footprint ""
		(layer "B.Cu")
		(at 178.599846 -301.599854 -90)
		(property "Reference" "C1473"
			(at 0 0 90)
			(layer "B.SilkS")
			(hide yes)
			(effects
				(font
					(size 1.27 1.27)
				)
				(justify mirror)
			)
		)
		(property "Value" ""
			(at 0 0 90)
			(layer "B.Fab")
			(effects
				(font
					(size 1.27 1.27)
				)
				(justify mirror)
			)
		)
		(duplicate_pad_numbers_are_jumpers no)
		(fp_line
			(start -0.299974 0.150114)
			(end 0.299974 0.150114)
			(stroke
				(width 0.1)
				(type default)
			)
			(layer "B.Fab")
		)
		(fp_line
			(start 0.299974 0.150114)
			(end 0.299974 -0.150114)
			(stroke
				(width 0.1)
				(type default)
			)
			(layer "B.Fab")
		)
		(fp_line
			(start -0.299974 -0.150114)
			(end -0.299974 0.150114)
			(stroke
				(width 0.1)
				(type default)
			)
			(layer "B.Fab")
		)
		(fp_line
			(start 0.299974 -0.150114)
			(end -0.299974 -0.150114)
			(stroke
				(width 0.1)
				(type default)
			)
			(layer "B.Fab")
		)
		(pad "1" smd rect
			(at 0.2667 0 90)
			(size 0.3048 0.381)
			(layers "B.Cu" "B.Mask" "B.Paste")
			(net "P0V8_SERDES_VDDA_PEX1")
		)
		(pad "2" smd rect
			(at -0.2667 0 90)
			(size 0.3048 0.381)
			(layers "B.Cu" "B.Mask" "B.Paste")
			(net "GND")
		)
	)
	(footprint ""
		(layer "B.Cu")
		(at 251.968 -199.39 -90)
		(property "Reference" "R6411"
			(at 0 0 90)
			(layer "B.SilkS")
			(hide yes)
			(effects
				(font
					(size 1.27 1.27)
				)
				(justify mirror)
			)
		)
		(property "Value" ""
			(at 0 0 90)
			(layer "B.Fab")
			(effects
				(font
					(size 1.27 1.27)
				)
				(justify mirror)
			)
		)
		(duplicate_pad_numbers_are_jumpers no)
		(fp_line
			(start -0.7874 0.4064)
			(end 0.7874 0.4064)
			(stroke
				(width 0.1524)
				(type default)
			)
			(layer "B.SilkS")
		)
		(fp_line
			(start 0.7874 0.4064)
			(end 0.7874 -0.4064)
			(stroke
				(width 0.1524)
				(type default)
			)
			(layer "B.SilkS")
		)
		(fp_line
			(start -0.7874 -0.4064)
			(end -0.7874 0.4064)
			(stroke
				(width 0.1524)
				(type default)
			)
			(layer "B.SilkS")
		)
		(fp_line
			(start 0.7874 -0.4064)
			(end -0.7874 -0.4064)
			(stroke
				(width 0.1524)
				(type default)
			)
			(layer "B.SilkS")
		)
		(fp_line
			(start -0.67945 0.3048)
			(end -0.120396 0.3048)
			(stroke
				(width 0.1)
				(type default)
			)
			(layer "B.Fab")
		)
		(fp_line
			(start -0.120396 0.3048)
			(end -0.120396 0.2794)
			(stroke
				(width 0.1)
				(type default)
			)
			(layer "B.Fab")
		)
		(fp_line
			(start 0.12065 0.3048)
			(end 0.67945 0.3048)
			(stroke
				(width 0.1)
				(type default)
			)
			(layer "B.Fab")
		)
		(fp_line
			(start 0.67945 0.3048)
			(end 0.67945 -0.305054)
			(stroke
				(width 0.1)
				(type default)
			)
			(layer "B.Fab")
		)
		(fp_line
			(start -0.120396 0.2794)
			(end 0.12065 0.2794)
			(stroke
				(width 0.1)
				(type default)
			)
			(layer "B.Fab")
		)
		(fp_line
			(start 0.12065 0.2794)
			(end 0.12065 0.3048)
			(stroke
				(width 0.1)
				(type default)
			)
			(layer "B.Fab")
		)
		(fp_line
			(start -0.12065 -0.2794)
			(end -0.12065 -0.3048)
			(stroke
				(width 0.1)
				(type default)
			)
			(layer "B.Fab")
		)
		(fp_line
			(start 0.12065 -0.2794)
			(end -0.12065 -0.2794)
			(stroke
				(width 0.1)
				(type default)
			)
			(layer "B.Fab")
		)
		(fp_line
			(start -0.67945 -0.3048)
			(end -0.67945 0.3048)
			(stroke
				(width 0.1)
				(type default)
			)
			(layer "B.Fab")
		)
		(fp_line
			(start -0.12065 -0.3048)
			(end -0.67945 -0.3048)
			(stroke
				(width 0.1)
				(type default)
			)
			(layer "B.Fab")
		)
		(fp_line
			(start 0.12065 -0.305054)
			(end 0.12065 -0.2794)
			(stroke
				(width 0.1)
				(type default)
			)
			(layer "B.Fab")
		)
		(fp_line
			(start 0.67945 -0.305054)
			(end 0.12065 -0.305054)
			(stroke
				(width 0.1)
				(type default)
			)
			(layer "B.Fab")
		)
		(pad "1" smd circle
			(at 0.40005 0 90)
			(size 0 0)
			(layers "B.Cu" "B.Mask" "B.Paste")
			(net "JTAG_BIC_EN_R")
		)
		(pad "2" smd circle
			(at -0.40005 0 90)
			(size 0 0)
			(layers "B.Cu" "B.Mask" "B.Paste")
			(net "GND")
		)
	)
	(footprint ""
		(layer "B.Cu")
		(at 100.154994 -330.01585 180)
		(property "Reference" "R1227"
			(at 0 0 0)
			(layer "B.SilkS")
			(hide yes)
			(effects
				(font
					(size 1.27 1.27)
				)
				(justify mirror)
			)
		)
		(property "Value" ""
			(at 0 0 0)
			(layer "B.Fab")
			(effects
				(font
					(size 1.27 1.27)
				)
				(justify mirror)
			)
		)
		(duplicate_pad_numbers_are_jumpers no)
		(fp_line
			(start 0.7874 0.4064)
			(end 0.7874 -0.4064)
			(stroke
				(width 0.1524)
				(type default)
			)
			(layer "B.SilkS")
		)
		(fp_line
			(start 0.7874 -0.4064)
			(end -0.7874 -0.4064)
			(stroke
				(width 0.1524)
				(type default)
			)
			(layer "B.SilkS")
		)
		(fp_line
			(start -0.7874 0.4064)
			(end 0.7874 0.4064)
			(stroke
				(width 0.1524)
				(type default)
			)
			(layer "B.SilkS")
		)
		(fp_line
			(start -0.7874 -0.4064)
			(end -0.7874 0.4064)
			(stroke
				(width 0.1524)
				(type default)
			)
			(layer "B.SilkS")
		)
		(fp_line
			(start 0.67945 0.3048)
			(end 0.67945 -0.305054)
			(stroke
				(width 0.1)
				(type default)
			)
			(layer "B.Fab")
		)
		(fp_line
			(start 0.67945 -0.305054)
			(end 0.12065 -0.305054)
			(stroke
				(width 0.1)
				(type default)
			)
			(layer "B.Fab")
		)
		(fp_line
			(start 0.12065 0.3048)
			(end 0.67945 0.3048)
			(stroke
				(width 0.1)
				(type default)
			)
			(layer "B.Fab")
		)
		(fp_line
			(start 0.12065 0.2794)
			(end 0.12065 0.3048)
			(stroke
				(width 0.1)
				(type default)
			)
			(layer "B.Fab")
		)
		(fp_line
			(start 0.12065 -0.2794)
			(end -0.12065 -0.2794)
			(stroke
				(width 0.1)
				(type default)
			)
			(layer "B.Fab")
		)
		(fp_line
			(start 0.12065 -0.305054)
			(end 0.12065 -0.2794)
			(stroke
				(width 0.1)
				(type default)
			)
			(layer "B.Fab")
		)
		(fp_line
			(start -0.120396 0.3048)
			(end -0.120396 0.2794)
			(stroke
				(width 0.1)
				(type default)
			)
			(layer "B.Fab")
		)
		(fp_line
			(start -0.120396 0.2794)
			(end 0.12065 0.2794)
			(stroke
				(width 0.1)
				(type default)
			)
			(layer "B.Fab")
		)
		(fp_line
			(start -0.12065 -0.2794)
			(end -0.12065 -0.3048)
			(stroke
				(width 0.1)
				(type default)
			)
			(layer "B.Fab")
		)
		(fp_line
			(start -0.12065 -0.3048)
			(end -0.67945 -0.3048)
			(stroke
				(width 0.1)
				(type default)
			)
			(layer "B.Fab")
		)
		(fp_line
			(start -0.67945 0.3048)
			(end -0.120396 0.3048)
			(stroke
				(width 0.1)
				(type default)
			)
			(layer "B.Fab")
		)
		(fp_line
			(start -0.67945 -0.3048)
			(end -0.67945 0.3048)
			(stroke
				(width 0.1)
				(type default)
			)
			(layer "B.Fab")
		)
		(pad "1" smd circle
			(at 0.40005 0)
			(size 0 0)
			(layers "B.Cu" "B.Mask" "B.Paste")
			(net "CLK_100M_DB800ZL_PEX1_S0_R_DP")
		)
		(pad "2" smd circle
			(at -0.40005 0)
			(size 0 0)
			(layers "B.Cu" "B.Mask" "B.Paste")
			(net "CLK_100M_DB800ZL_PEX1_S0_DP")
		)
	)
)
